(kicad_pcb
	(version 20260206)
	(generator "pcbnew")
	(generator_version "10.0")
	(general
		(thickness 1.6)
		(legacy_teardrops no)
	)
	(paper "A4")
	(title_block
		(title "01162023_DA0F0TEBIF0_F0T_Expander_BD_F_brd_V02_OCP.brd")
		(comment 1 "Grand Teton / footprints 8184-8193 of 9728")
	)
	(layers
		(0 "F.Cu" signal "TOP")
		(4 "In1.Cu" signal "GND")
		(6 "In2.Cu" signal "VCC")
		(8 "In3.Cu" signal "VCC1")
		(10 "In4.Cu" signal "GND1")
		(12 "In5.Cu" signal "IN1")
		(14 "In6.Cu" signal "GND2")
		(16 "In7.Cu" signal "IN2")
		(18 "In8.Cu" signal "GND3")
		(20 "In9.Cu" signal "IN3")
		(22 "In10.Cu" signal "GND4")
		(24 "In11.Cu" signal "IN4")
		(26 "In12.Cu" signal "GND5")
		(28 "In13.Cu" signal "IN5")
		(30 "In14.Cu" signal "GND6")
		(32 "In15.Cu" signal "IN6")
		(34 "In16.Cu" signal "GND7")
		(2 "B.Cu" signal "BOTTOM")
		(9 "F.Adhes" user "F.Adhesive")
		(11 "B.Adhes" user "B.Adhesive")
		(13 "F.Paste" user "Package Geometry/Pastemask Top")
		(15 "B.Paste" user "Package Geometry/Pastemask Bottom")
		(5 "F.SilkS" user "Ref Des/Silkscreen Top")
		(7 "B.SilkS" user "Ref Des/Silkscreen Bottom")
		(1 "F.Mask" user "Board Geometry/Soldermask Top")
		(3 "B.Mask" user "Board Geometry/Soldermask Bottom")
		(17 "Dwgs.User" user "User.Drawings")
		(19 "Cmts.User" user "User.Comments")
		(21 "Eco1.User" user "User.Eco1")
		(23 "Eco2.User" user "User.Eco2")
		(25 "Edge.Cuts" user "Board Geometry/Outline")
		(27 "Margin" user)
		(31 "F.CrtYd" user "Package Geometry/Place Bound Top")
		(29 "B.CrtYd" user "Package Geometry/Place Bound Bottom")
		(35 "F.Fab" user "Ref Des/Assembly Top")
		(33 "B.Fab" user "Ref Des/Assembly Bottom")
	)
	(footprint ""
		(layer "B.Cu")
		(at 333.63916 -82.569558 90)
		(property "Reference" "C2673"
			(at 0 0 90)
			(layer "B.SilkS")
			(hide yes)
			(effects
				(font
					(size 1.27 1.27)
				)
				(justify mirror)
			)
		)
		(property "Value" ""
			(at 0 0 90)
			(layer "B.Fab")
			(effects
				(font
					(size 1.27 1.27)
				)
				(justify mirror)
			)
		)
		(duplicate_pad_numbers_are_jumpers no)
		(fp_line
			(start 1.524 -0.762)
			(end -1.524 -0.762)
			(stroke
				(width 0.1524)
				(type default)
			)
			(layer "B.SilkS")
		)
		(fp_line
			(start -1.524 -0.762)
			(end -1.524 0.762)
			(stroke
				(width 0.1524)
				(type default)
			)
			(layer "B.SilkS")
		)
		(fp_line
			(start 1.524 0.762)
			(end 1.524 -0.762)
			(stroke
				(width 0.1524)
				(type default)
			)
			(layer "B.SilkS")
		)
		(fp_line
			(start -1.524 0.762)
			(end 1.524 0.762)
			(stroke
				(width 0.1524)
				(type default)
			)
			(layer "B.SilkS")
		)
		(fp_line
			(start 1.1049 -0.724916)
			(end 1.1049 0.724916)
			(stroke
				(width 0.1)
				(type default)
			)
			(layer "B.Fab")
		)
		(fp_line
			(start -1.1049 -0.724916)
			(end 1.1049 -0.724916)
			(stroke
				(width 0.1)
				(type default)
			)
			(layer "B.Fab")
		)
		(fp_line
			(start 1.1049 0.724916)
			(end -1.1049 0.724916)
			(stroke
				(width 0.1)
				(type default)
			)
			(layer "B.Fab")
		)
		(fp_line
			(start -1.1049 0.724916)
			(end -1.1049 -0.724916)
			(stroke
				(width 0.1)
				(type default)
			)
			(layer "B.Fab")
		)
		(pad "1" smd rect
			(at 0.889 0 90)
			(size 1.016 1.27)
			(layers "B.Cu" "B.Mask" "B.Paste")
			(net "P3V3_VDD_9ZXL0851_8_15")
		)
		(pad "2" smd rect
			(at -0.889 0 90)
			(size 1.016 1.27)
			(layers "B.Cu" "B.Mask" "B.Paste")
			(net "GND")
		)
	)
	(footprint ""
		(layer "B.Cu")
		(at 50.624994 -297.79976 -90)
		(property "Reference" "C1138"
			(at 0 0 90)
			(layer "B.SilkS")
			(hide yes)
			(effects
				(font
					(size 1.27 1.27)
				)
				(justify mirror)
			)
		)
		(property "Value" ""
			(at 0 0 90)
			(layer "B.Fab")
			(effects
				(font
					(size 1.27 1.27)
				)
				(justify mirror)
			)
		)
		(duplicate_pad_numbers_are_jumpers no)
		(fp_line
			(start -0.299974 0.150114)
			(end 0.299974 0.150114)
			(stroke
				(width 0.1)
				(type default)
			)
			(layer "B.Fab")
		)
		(fp_line
			(start 0.299974 0.150114)
			(end 0.299974 -0.150114)
			(stroke
				(width 0.1)
				(type default)
			)
			(layer "B.Fab")
		)
		(fp_line
			(start -0.299974 -0.150114)
			(end -0.299974 0.150114)
			(stroke
				(width 0.1)
				(type default)
			)
			(layer "B.Fab")
		)
		(fp_line
			(start 0.299974 -0.150114)
			(end -0.299974 -0.150114)
			(stroke
				(width 0.1)
				(type default)
			)
			(layer "B.Fab")
		)
		(pad "1" smd rect
			(at 0.2667 0 90)
			(size 0.3048 0.381)
			(layers "B.Cu" "B.Mask" "B.Paste")
			(net "P0V8_PEX0")
		)
		(pad "2" smd rect
			(at -0.2667 0 90)
			(size 0.3048 0.381)
			(layers "B.Cu" "B.Mask" "B.Paste")
			(net "GND")
		)
	)
	(footprint ""
		(layer "B.Cu")
		(at 51.52009 -305.399948 -90)
		(property "Reference" "C2983"
			(at 0 0 90)
			(layer "B.SilkS")
			(hide yes)
			(effects
				(font
					(size 1.27 1.27)
				)
				(justify mirror)
			)
		)
		(property "Value" ""
			(at 0 0 90)
			(layer "B.Fab")
			(effects
				(font
					(size 1.27 1.27)
				)
				(justify mirror)
			)
		)
		(duplicate_pad_numbers_are_jumpers no)
		(fp_line
			(start -0.299974 0.150114)
			(end 0.299974 0.150114)
			(stroke
				(width 0.1)
				(type default)
			)
			(layer "B.Fab")
		)
		(fp_line
			(start 0.299974 0.150114)
			(end 0.299974 -0.150114)
			(stroke
				(width 0.1)
				(type default)
			)
			(layer "B.Fab")
		)
		(fp_line
			(start -0.299974 -0.150114)
			(end -0.299974 0.150114)
			(stroke
				(width 0.1)
				(type default)
			)
			(layer "B.Fab")
		)
		(fp_line
			(start 0.299974 -0.150114)
			(end -0.299974 -0.150114)
			(stroke
				(width 0.1)
				(type default)
			)
			(layer "B.Fab")
		)
		(pad "1" smd rect
			(at 0.2667 0 90)
			(size 0.3048 0.381)
			(layers "B.Cu" "B.Mask" "B.Paste")
			(net "P1V25_SERDES_VDDPLL_PEX0")
		)
		(pad "2" smd rect
			(at -0.2667 0 90)
			(size 0.3048 0.381)
			(layers "B.Cu" "B.Mask" "B.Paste")
			(net "GND")
		)
	)
	(footprint ""
		(layer "B.Cu")
		(at 299.067474 -223.599502 90)
		(property "Reference" "R1861"
			(at 0 0 90)
			(layer "B.SilkS")
			(hide yes)
			(effects
				(font
					(size 1.27 1.27)
				)
				(justify mirror)
			)
		)
		(property "Value" ""
			(at 0 0 90)
			(layer "B.Fab")
			(effects
				(font
					(size 1.27 1.27)
				)
				(justify mirror)
			)
		)
		(duplicate_pad_numbers_are_jumpers no)
		(fp_line
			(start 0.7874 -0.4064)
			(end -0.7874 -0.4064)
			(stroke
				(width 0.1524)
				(type default)
			)
			(layer "B.SilkS")
		)
		(fp_line
			(start -0.7874 -0.4064)
			(end -0.7874 0.4064)
			(stroke
				(width 0.1524)
				(type default)
			)
			(layer "B.SilkS")
		)
		(fp_line
			(start 0.7874 0.4064)
			(end 0.7874 -0.4064)
			(stroke
				(width 0.1524)
				(type default)
			)
			(layer "B.SilkS")
		)
		(fp_line
			(start -0.7874 0.4064)
			(end 0.7874 0.4064)
			(stroke
				(width 0.1524)
				(type default)
			)
			(layer "B.SilkS")
		)
		(fp_line
			(start 0.67945 -0.305054)
			(end 0.12065 -0.305054)
			(stroke
				(width 0.1)
				(type default)
			)
			(layer "B.Fab")
		)
		(fp_line
			(start 0.12065 -0.305054)
			(end 0.12065 -0.2794)
			(stroke
				(width 0.1)
				(type default)
			)
			(layer "B.Fab")
		)
		(fp_line
			(start -0.12065 -0.3048)
			(end -0.67945 -0.3048)
			(stroke
				(width 0.1)
				(type default)
			)
			(layer "B.Fab")
		)
		(fp_line
			(start -0.67945 -0.3048)
			(end -0.67945 0.3048)
			(stroke
				(width 0.1)
				(type default)
			)
			(layer "B.Fab")
		)
		(fp_line
			(start 0.12065 -0.2794)
			(end -0.12065 -0.2794)
			(stroke
				(width 0.1)
				(type default)
			)
			(layer "B.Fab")
		)
		(fp_line
			(start -0.12065 -0.2794)
			(end -0.12065 -0.3048)
			(stroke
				(width 0.1)
				(type default)
			)
			(layer "B.Fab")
		)
		(fp_line
			(start 0.12065 0.2794)
			(end 0.12065 0.3048)
			(stroke
				(width 0.1)
				(type default)
			)
			(layer "B.Fab")
		)
		(fp_line
			(start -0.120396 0.2794)
			(end 0.12065 0.2794)
			(stroke
				(width 0.1)
				(type default)
			)
			(layer "B.Fab")
		)
		(fp_line
			(start 0.67945 0.3048)
			(end 0.67945 -0.305054)
			(stroke
				(width 0.1)
				(type default)
			)
			(layer "B.Fab")
		)
		(fp_line
			(start 0.12065 0.3048)
			(end 0.67945 0.3048)
			(stroke
				(width 0.1)
				(type default)
			)
			(layer "B.Fab")
		)
		(fp_line
			(start -0.120396 0.3048)
			(end -0.120396 0.2794)
			(stroke
				(width 0.1)
				(type default)
			)
			(layer "B.Fab")
		)
		(fp_line
			(start -0.67945 0.3048)
			(end -0.120396 0.3048)
			(stroke
				(width 0.1)
				(type default)
			)
			(layer "B.Fab")
		)
		(pad "1" smd circle
			(at 0.40005 0 270)
			(size 0 0)
			(layers "B.Cu" "B.Mask" "B.Paste")
			(net "P3V3_AUX")
		)
		(pad "2" smd circle
			(at -0.40005 0 270)
			(size 0 0)
			(layers "B.Cu" "B.Mask" "B.Paste")
			(net "RST_GPU_PERST_0_BUF_N")
		)
	)
	(footprint ""
		(layer "B.Cu")
		(at 189.500002 -110.115096)
		(property "Reference" "C894"
			(at 0 0 0)
			(layer "B.SilkS")
			(hide yes)
			(effects
				(font
					(size 1.27 1.27)
				)
				(justify mirror)
			)
		)
		(property "Value" ""
			(at 0 0 0)
			(layer "B.Fab")
			(effects
				(font
					(size 1.27 1.27)
				)
				(justify mirror)
			)
		)
		(duplicate_pad_numbers_are_jumpers no)
		(fp_line
			(start -0.299974 -0.150114)
			(end -0.299974 0.150114)
			(stroke
				(width 0.1)
				(type default)
			)
			(layer "B.Fab")
		)
		(fp_line
			(start -0.299974 0.150114)
			(end 0.299974 0.150114)
			(stroke
				(width 0.1)
				(type default)
			)
			(layer "B.Fab")
		)
		(fp_line
			(start 0.299974 -0.150114)
			(end -0.299974 -0.150114)
			(stroke
				(width 0.1)
				(type default)
			)
			(layer "B.Fab")
		)
		(fp_line
			(start 0.299974 0.150114)
			(end 0.299974 -0.150114)
			(stroke
				(width 0.1)
				(type default)
			)
			(layer "B.Fab")
		)
		(pad "1" smd rect
			(at 0.2667 0 180)
			(size 0.3048 0.381)
			(layers "B.Cu" "B.Mask" "B.Paste")
			(net "P12V_NIC3")
		)
		(pad "2" smd rect
			(at -0.2667 0 180)
			(size 0.3048 0.381)
			(layers "B.Cu" "B.Mask" "B.Paste")
			(net "GND")
		)
	)
	(footprint ""
		(layer "B.Cu")
		(at 234.227878 -276.86381)
		(property "Reference" "C4349"
			(at 0 0 0)
			(layer "B.SilkS")
			(hide yes)
			(effects
				(font
					(size 1.27 1.27)
				)
				(justify mirror)
			)
		)
		(property "Value" ""
			(at 0 0 0)
			(layer "B.Fab")
			(effects
				(font
					(size 1.27 1.27)
				)
				(justify mirror)
			)
		)
		(duplicate_pad_numbers_are_jumpers no)
		(fp_line
			(start -0.299974 -0.150114)
			(end -0.299974 0.150114)
			(stroke
				(width 0.1)
				(type default)
			)
			(layer "B.Fab")
		)
		(fp_line
			(start -0.299974 0.150114)
			(end 0.299974 0.150114)
			(stroke
				(width 0.1)
				(type default)
			)
			(layer "B.Fab")
		)
		(fp_line
			(start 0.299974 -0.150114)
			(end -0.299974 -0.150114)
			(stroke
				(width 0.1)
				(type default)
			)
			(layer "B.Fab")
		)
		(fp_line
			(start 0.299974 0.150114)
			(end 0.299974 -0.150114)
			(stroke
				(width 0.1)
				(type default)
			)
			(layer "B.Fab")
		)
		(pad "1" smd rect
			(at 0.2667 0 180)
			(size 0.3048 0.381)
			(layers "B.Cu" "B.Mask" "B.Paste")
			(net "P1V25_PEX2")
		)
		(pad "2" smd rect
			(at -0.2667 0 180)
			(size 0.3048 0.381)
			(layers "B.Cu" "B.Mask" "B.Paste")
			(net "GND")
		)
	)
	(footprint ""
		(layer "B.Cu")
		(at 335.12887 -284.796738 -90)
		(property "Reference" "PC140"
			(at 0 0 90)
			(layer "B.SilkS")
			(hide yes)
			(effects
				(font
					(size 1.27 1.27)
				)
				(justify mirror)
			)
		)
		(property "Value" ""
			(at 0 0 90)
			(layer "B.Fab")
			(effects
				(font
					(size 1.27 1.27)
				)
				(justify mirror)
			)
		)
		(duplicate_pad_numbers_are_jumpers no)
		(fp_line
			(start -1.524 0.762)
			(end 1.524 0.762)
			(stroke
				(width 0.1524)
				(type default)
			)
			(layer "B.SilkS")
		)
		(fp_line
			(start 1.524 0.762)
			(end 1.524 -0.762)
			(stroke
				(width 0.1524)
				(type default)
			)
			(layer "B.SilkS")
		)
		(fp_line
			(start -1.524 -0.762)
			(end -1.524 0.762)
			(stroke
				(width 0.1524)
				(type default)
			)
			(layer "B.SilkS")
		)
		(fp_line
			(start 1.524 -0.762)
			(end -1.524 -0.762)
			(stroke
				(width 0.1524)
				(type default)
			)
			(layer "B.SilkS")
		)
		(fp_line
			(start -1.1049 0.724916)
			(end -1.1049 -0.724916)
			(stroke
				(width 0.1)
				(type default)
			)
			(layer "B.Fab")
		)
		(fp_line
			(start 1.1049 0.724916)
			(end -1.1049 0.724916)
			(stroke
				(width 0.1)
				(type default)
			)
			(layer "B.Fab")
		)
		(fp_line
			(start -1.1049 -0.724916)
			(end 1.1049 -0.724916)
			(stroke
				(width 0.1)
				(type default)
			)
			(layer "B.Fab")
		)
		(fp_line
			(start 1.1049 -0.724916)
			(end 1.1049 0.724916)
			(stroke
				(width 0.1)
				(type default)
			)
			(layer "B.Fab")
		)
		(pad "1" smd rect
			(at 0.889 0 270)
			(size 1.016 1.27)
			(layers "B.Cu" "B.Mask" "B.Paste")
			(net "SW_P12V_P0V8_PEX2_FLT")
		)
		(pad "2" smd rect
			(at -0.889 0 270)
			(size 1.016 1.27)
			(layers "B.Cu" "B.Mask" "B.Paste")
			(net "GND")
		)
	)
	(footprint ""
		(layer "B.Cu")
		(at 105.99547 -346.801186 -90)
		(property "Reference" "R6365"
			(at 0 0 90)
			(layer "B.SilkS")
			(hide yes)
			(effects
				(font
					(size 1.27 1.27)
				)
				(justify mirror)
			)
		)
		(property "Value" ""
			(at 0 0 90)
			(layer "B.Fab")
			(effects
				(font
					(size 1.27 1.27)
				)
				(justify mirror)
			)
		)
		(duplicate_pad_numbers_are_jumpers no)
		(fp_line
			(start -1.2954 0.5842)
			(end 1.2954 0.5842)
			(stroke
				(width 0.1524)
				(type default)
			)
			(layer "B.SilkS")
		)
		(fp_line
			(start 1.2954 0.5842)
			(end 1.2954 -0.5842)
			(stroke
				(width 0.1524)
				(type default)
			)
			(layer "B.SilkS")
		)
		(fp_line
			(start -1.2954 -0.5842)
			(end -1.2954 0.5842)
			(stroke
				(width 0.1524)
				(type default)
			)
			(layer "B.SilkS")
		)
		(fp_line
			(start 1.2954 -0.5842)
			(end -1.2954 -0.5842)
			(stroke
				(width 0.1524)
				(type default)
			)
			(layer "B.SilkS")
		)
		(fp_line
			(start -0.8636 0.4572)
			(end 0.8636 0.4572)
			(stroke
				(width 0.1)
				(type default)
			)
			(layer "B.Fab")
		)
		(fp_line
			(start 0.8636 0.4572)
			(end 0.8636 0.4318)
			(stroke
				(width 0.1)
				(type default)
			)
			(layer "B.Fab")
		)
		(fp_line
			(start 0.8636 0.4318)
			(end 0.8636 0.4064)
			(stroke
				(width 0.1)
				(type default)
			)
			(layer "B.Fab")
		)
		(fp_line
			(start -1.1938 0.4064)
			(end -0.8636 0.4064)
			(stroke
				(width 0.1)
				(type default)
			)
			(layer "B.Fab")
		)
		(fp_line
			(start -0.8636 0.4064)
			(end -0.8636 0.4572)
			(stroke
				(width 0.1)
				(type default)
			)
			(layer "B.Fab")
		)
		(fp_line
			(start 0.8636 0.4064)
			(end 1.1938 0.4064)
			(stroke
				(width 0.1)
				(type default)
			)
			(layer "B.Fab")
		)
		(fp_line
			(start 1.1938 0.4064)
			(end 1.1938 -0.406654)
			(stroke
				(width 0.1)
				(type default)
			)
			(layer "B.Fab")
		)
		(fp_line
			(start -1.1938 -0.406654)
			(end -1.1938 0.4064)
			(stroke
				(width 0.1)
				(type default)
			)
			(layer "B.Fab")
		)
		(fp_line
			(start -0.8636 -0.406654)
			(end -1.1938 -0.406654)
			(stroke
				(width 0.1)
				(type default)
			)
			(layer "B.Fab")
		)
		(fp_line
			(start 0.8636 -0.406654)
			(end 0.8636 -0.4572)
			(stroke
				(width 0.1)
				(type default)
			)
			(layer "B.Fab")
		)
		(fp_line
			(start 1.1938 -0.406654)
			(end 0.8636 -0.406654)
			(stroke
				(width 0.1)
				(type default)
			)
			(layer "B.Fab")
		)
		(fp_line
			(start -0.8636 -0.4572)
			(end -0.8636 -0.406654)
			(stroke
				(width 0.1)
				(type default)
			)
			(layer "B.Fab")
		)
		(fp_line
			(start 0.8636 -0.4572)
			(end -0.8636 -0.4572)
			(stroke
				(width 0.1)
				(type default)
			)
			(layer "B.Fab")
		)
		(pad "1" smd rect
			(at 0.7366 0 180)
			(size 0.7112 0.8128)
			(layers "B.Cu" "B.Mask" "B.Paste")
			(net "P3V3_CLK_BUFFER_9ZXL0451E_S3_VZX3P3")
		)
		(pad "2" smd rect
			(at -0.7366 0 180)
			(size 0.7112 0.8128)
			(layers "B.Cu" "B.Mask" "B.Paste")
			(net "P3V3_CLK_BUFFER_9ZXL0451E_S3_VZX3P3A")
		)
	)
	(footprint ""
		(layer "B.Cu")
		(at 303.486312 -117.66169)
		(property "Reference" "R258"
			(at 0 0 0)
			(layer "B.SilkS")
			(hide yes)
			(effects
				(font
					(size 1.27 1.27)
				)
				(justify mirror)
			)
		)
		(property "Value" ""
			(at 0 0 0)
			(layer "B.Fab")
			(effects
				(font
					(size 1.27 1.27)
				)
				(justify mirror)
			)
		)
		(duplicate_pad_numbers_are_jumpers no)
		(fp_line
			(start -0.7874 -0.4064)
			(end -0.7874 0.4064)
			(stroke
				(width 0.1524)
				(type default)
			)
			(layer "B.SilkS")
		)
		(fp_line
			(start -0.7874 0.4064)
			(end 0.7874 0.4064)
			(stroke
				(width 0.1524)
				(type default)
			)
			(layer "B.SilkS")
		)
		(fp_line
			(start 0.7874 -0.4064)
			(end -0.7874 -0.4064)
			(stroke
				(width 0.1524)
				(type default)
			)
			(layer "B.SilkS")
		)
		(fp_line
			(start 0.7874 0.4064)
			(end 0.7874 -0.4064)
			(stroke
				(width 0.1524)
				(type default)
			)
			(layer "B.SilkS")
		)
		(fp_line
			(start -0.67945 -0.3048)
			(end -0.67945 0.3048)
			(stroke
				(width 0.1)
				(type default)
			)
			(layer "B.Fab")
		)
		(fp_line
			(start -0.67945 0.3048)
			(end -0.120396 0.3048)
			(stroke
				(width 0.1)
				(type default)
			)
			(layer "B.Fab")
		)
		(fp_line
			(start -0.12065 -0.3048)
			(end -0.67945 -0.3048)
			(stroke
				(width 0.1)
				(type default)
			)
			(layer "B.Fab")
		)
		(fp_line
			(start -0.12065 -0.2794)
			(end -0.12065 -0.3048)
			(stroke
				(width 0.1)
				(type default)
			)
			(layer "B.Fab")
		)
		(fp_line
			(start -0.120396 0.2794)
			(end 0.12065 0.2794)
			(stroke
				(width 0.1)
				(type default)
			)
			(layer "B.Fab")
		)
		(fp_line
			(start -0.120396 0.3048)
			(end -0.120396 0.2794)
			(stroke
				(width 0.1)
				(type default)
			)
			(layer "B.Fab")
		)
		(fp_line
			(start 0.12065 -0.305054)
			(end 0.12065 -0.2794)
			(stroke
				(width 0.1)
				(type default)
			)
			(layer "B.Fab")
		)
		(fp_line
			(start 0.12065 -0.2794)
			(end -0.12065 -0.2794)
			(stroke
				(width 0.1)
				(type default)
			)
			(layer "B.Fab")
		)
		(fp_line
			(start 0.12065 0.2794)
			(end 0.12065 0.3048)
			(stroke
				(width 0.1)
				(type default)
			)
			(layer "B.Fab")
		)
		(fp_line
			(start 0.12065 0.3048)
			(end 0.67945 0.3048)
			(stroke
				(width 0.1)
				(type default)
			)
			(layer "B.Fab")
		)
		(fp_line
			(start 0.67945 -0.305054)
			(end 0.12065 -0.305054)
			(stroke
				(width 0.1)
				(type default)
			)
			(layer "B.Fab")
		)
		(fp_line
			(start 0.67945 0.3048)
			(end 0.67945 -0.305054)
			(stroke
				(width 0.1)
				(type default)
			)
			(layer "B.Fab")
		)
		(pad "1" smd circle
			(at 0.40005 0 180)
			(size 0 0)
			(layers "B.Cu" "B.Mask" "B.Paste")
			(net "NIC5_AUX_PWR_EN_R")
		)
		(pad "2" smd circle
			(at -0.40005 0 180)
			(size 0 0)
			(layers "B.Cu" "B.Mask" "B.Paste")
			(net "NIC5_AUX_PWR_EN")
		)
	)
	(footprint ""
		(layer "B.Cu")
		(at 173.850046 -301.599854 -90)
		(property "Reference" "C1459"
			(at 0 0 90)
			(layer "B.SilkS")
			(hide yes)
			(effects
				(font
					(size 1.27 1.27)
				)
				(justify mirror)
			)
		)
		(property "Value" ""
			(at 0 0 90)
			(layer "B.Fab")
			(effects
				(font
					(size 1.27 1.27)
				)
				(justify mirror)
			)
		)
		(duplicate_pad_numbers_are_jumpers no)
		(fp_line
			(start -0.299974 0.150114)
			(end 0.299974 0.150114)
			(stroke
				(width 0.1)
				(type default)
			)
			(layer "B.Fab")
		)
		(fp_line
			(start 0.299974 0.150114)
			(end 0.299974 -0.150114)
			(stroke
				(width 0.1)
				(type default)
			)
			(layer "B.Fab")
		)
		(fp_line
			(start -0.299974 -0.150114)
			(end -0.299974 0.150114)
			(stroke
				(width 0.1)
				(type default)
			)
			(layer "B.Fab")
		)
		(fp_line
			(start 0.299974 -0.150114)
			(end -0.299974 -0.150114)
			(stroke
				(width 0.1)
				(type default)
			)
			(layer "B.Fab")
		)
		(pad "1" smd rect
			(at 0.2667 0 90)
			(size 0.3048 0.381)
			(layers "B.Cu" "B.Mask" "B.Paste")
			(net "P0V8_SERDES_VDDA_PEX1")
		)
		(pad "2" smd rect
			(at -0.2667 0 90)
			(size 0.3048 0.381)
			(layers "B.Cu" "B.Mask" "B.Paste")
			(net "GND")
		)
	)
)
